# SCM (Grand Teton) — schematic netlist excerpt (pin names and nets, part order shuffled) for the footprints in the layout excerpt that follows; sources: Cadence DE-HDL packaged netlist, KiCad conversion of 12092022_DA0F0TMDCD0_F0T_Management_Board_D_brd_V3_OCP.brd

R199  Q_RES  33.2 1% CHIP  pkg 0402LF  page 14 : A = I3C3_SDA_R ; B = I3C3_SPD_SDA

Q2  MOSFET_NCH_DUAL  2N7002KDW IC  pkg SOT363XD  page 23
  S1  = V_BMC_DDC_SDA
  G1  = V_BMC_DDC_LS_GATE
  D2  = V_BMC_LS_DDC_SCL
  S2  = V_BMC_DDC_SCL
  G2  = V_BMC_DDC_LS_GATE
  D1  = V_BMC_LS_DDC_SDA

(kicad_pcb
	(version 20260206)
	(generator "pcbnew")
	(generator_version "10.0")
	(general
		(thickness 1.6)
		(legacy_teardrops no)
	)
	(paper "A4")
	(title_block
		(title "12092022_DA0F0TMDCD0_F0T_Management_Board_D_brd_V3_OCP.brd")
		(comment 1 "Grand Teton / footprints 524-526 of 1440")
	)
	(layers
		(0 "F.Cu" signal "TOP")
		(4 "In1.Cu" signal "GND")
		(6 "In2.Cu" signal "IN1")
		(8 "In3.Cu" signal "GND1")
		(10 "In4.Cu" signal "IN2")
		(12 "In5.Cu" signal "VCC")
		(14 "In6.Cu" signal "VCC1")
		(16 "In7.Cu" signal "IN3")
		(18 "In8.Cu" signal "GND2")
		(20 "In9.Cu" signal "IN4")
		(22 "In10.Cu" signal "GND3")
		(2 "B.Cu" signal "BOTTOM")
		(9 "F.Adhes" user "F.Adhesive")
		(11 "B.Adhes" user "B.Adhesive")
		(13 "F.Paste" user "Package Geometry/Pastemask Top")
		(15 "B.Paste" user "Package Geometry/Pastemask Bottom")
		(5 "F.SilkS" user "Ref Des/Silkscreen Top")
		(7 "B.SilkS" user "Ref Des/Silkscreen Bottom")
		(1 "F.Mask" user "Board Geometry/Soldermask Top")
		(3 "B.Mask" user "Board Geometry/Soldermask Bottom")
		(17 "Dwgs.User" user "User.Drawings")
		(19 "Cmts.User" user "User.Comments")
		(21 "Eco1.User" user "User.Eco1")
		(23 "Eco2.User" user "User.Eco2")
		(25 "Edge.Cuts" user "Board Geometry/Outline")
		(27 "Margin" user)
		(31 "F.CrtYd" user "Package Geometry/Place Bound Top")
		(29 "B.CrtYd" user "Package Geometry/Place Bound Bottom")
		(35 "F.Fab" user "Ref Des/Assembly Top")
		(33 "B.Fab" user "Ref Des/Assembly Bottom")
	)
	(footprint ""
		(layer "F.Cu")
		(at 29.845 -19.558 180)
		(property "Reference" "Q2"
			(at 2.921 -1.305052 0)
			(unlocked yes)
			(layer "F.SilkS")
			(effects
				(font
					(size 0.7874 0.5842)
					(thickness 0.1524)
				)
				(justify left)
			)
		)
		(property "Value" ""
			(at 0 0 180)
			(layer "F.Fab")
			(effects
				(font
					(size 1.27 1.27)
				)
			)
		)
		(duplicate_pad_numbers_are_jumpers no)
		(fp_line
			(start 1.332738 1.100074)
			(end -1.332738 1.100074)
			(stroke
				(width 0.1524)
				(type default)
			)
			(layer "F.SilkS")
		)
		(fp_line
			(start 1.332738 -1.100074)
			(end 1.332738 1.100074)
			(stroke
				(width 0.1524)
				(type default)
			)
			(layer "F.SilkS")
		)
		(fp_line
			(start 0.4826 -1.100074)
			(end 1.332738 -1.100074)
			(stroke
				(width 0.1524)
				(type default)
			)
			(layer "F.SilkS")
		)
		(fp_line
			(start 0 -0.541274)
			(end 0.4826 -1.100074)
			(stroke
				(width 0.1524)
				(type default)
			)
			(layer "F.SilkS")
		)
		(fp_line
			(start -0.4826 -1.100074)
			(end 0 -0.541274)
			(stroke
				(width 0.1524)
				(type default)
			)
			(layer "F.SilkS")
		)
		(fp_line
			(start -1.332738 1.100074)
			(end -1.332738 -1.100074)
			(stroke
				(width 0.1524)
				(type default)
			)
			(layer "F.SilkS")
		)
		(fp_line
			(start -1.332738 -1.100074)
			(end -0.4826 -1.100074)
			(stroke
				(width 0.1524)
				(type default)
			)
			(layer "F.SilkS")
		)
		(fp_poly
			(pts
				(xy -2.2352 -0.298958) (xy -2.2352 -1.001014) (xy -1.533144 -0.649986)
			)
			(stroke
				(width 0)
				(type default)
			)
			(fill yes)
			(layer "F.SilkS")
		)
		(fp_line
			(start 0.674878 1.100074)
			(end -0.674878 1.100074)
			(stroke
				(width 0.1)
				(type default)
			)
			(layer "F.Fab")
		)
		(fp_line
			(start 0.674878 -1.100074)
			(end 0.674878 1.100074)
			(stroke
				(width 0.1)
				(type default)
			)
			(layer "F.Fab")
		)
		(fp_line
			(start -0.674878 1.100074)
			(end -0.674878 -1.100074)
			(stroke
				(width 0.1)
				(type default)
			)
			(layer "F.Fab")
		)
		(fp_line
			(start -0.674878 -1.100074)
			(end 0.674878 -1.100074)
			(stroke
				(width 0.1)
				(type default)
			)
			(layer "F.Fab")
		)
		(fp_poly
			(pts
				(xy -2.2352 -0.298958) (xy -2.2352 -1.001014) (xy -1.533144 -0.649986)
			)
			(stroke
				(width 0)
				(type default)
			)
			(fill yes)
			(layer "F.Fab")
		)
		(pad "1" smd rect
			(at -0.94996 -0.649986 270)
			(size 0.4318 0.508)
			(layers "F.Cu" "F.Mask" "F.Paste")
			(net "V_BMC_DDC_SDA")
		)
		(pad "2" smd rect
			(at -0.94996 0 270)
			(size 0.4318 0.508)
			(layers "F.Cu" "F.Mask" "F.Paste")
			(net "V_BMC_DDC_LS_GATE")
		)
		(pad "3" smd rect
			(at -0.94996 0.649986 270)
			(size 0.4318 0.508)
			(layers "F.Cu" "F.Mask" "F.Paste")
			(net "V_BMC_LS_DDC_SCL")
		)
		(pad "4" smd rect
			(at 0.94996 0.649986 270)
			(size 0.4318 0.508)
			(layers "F.Cu" "F.Mask" "F.Paste")
			(net "V_BMC_DDC_SCL")
		)
		(pad "5" smd rect
			(at 0.94996 0 270)
			(size 0.4318 0.508)
			(layers "F.Cu" "F.Mask" "F.Paste")
			(net "V_BMC_DDC_LS_GATE")
		)
		(pad "6" smd rect
			(at 0.94996 -0.649986 270)
			(size 0.4318 0.508)
			(layers "F.Cu" "F.Mask" "F.Paste")
			(net "V_BMC_LS_DDC_SDA")
		)
	)
	(footprint ""
		(layer "F.Cu")
		(at 39.805102 -65.793366 90)
		(property "Reference" "R199"
			(at 0 0 90)
			(layer "F.SilkS")
			(hide yes)
			(effects
				(font
					(size 1.27 1.27)
				)
			)
		)
		(property "Value" ""
			(at 0 0 90)
			(layer "F.Fab")
			(effects
				(font
					(size 1.27 1.27)
				)
			)
		)
		(duplicate_pad_numbers_are_jumpers no)
		(fp_line
			(start 0.7874 -0.4064)
			(end 0.7874 0.4064)
			(stroke
				(width 0.1524)
				(type default)
			)
			(layer "F.SilkS")
		)
		(fp_line
			(start -0.7874 -0.4064)
			(end 0.7874 -0.4064)
			(stroke
				(width 0.1524)
				(type default)
			)
			(layer "F.SilkS")
		)
		(fp_line
			(start 0.7874 0.4064)
			(end -0.7874 0.4064)
			(stroke
				(width 0.1524)
				(type default)
			)
			(layer "F.SilkS")
		)
		(fp_line
			(start -0.7874 0.4064)
			(end -0.7874 -0.4064)
			(stroke
				(width 0.1524)
				(type default)
			)
			(layer "F.SilkS")
		)
		(fp_line
			(start -0.12065 -0.305054)
			(end -0.12065 -0.2794)
			(stroke
				(width 0.1)
				(type default)
			)
			(layer "F.Fab")
		)
		(fp_line
			(start -0.67945 -0.305054)
			(end -0.12065 -0.305054)
			(stroke
				(width 0.1)
				(type default)
			)
			(layer "F.Fab")
		)
		(fp_line
			(start 0.67945 -0.3048)
			(end 0.67945 0.3048)
			(stroke
				(width 0.1)
				(type default)
			)
			(layer "F.Fab")
		)
		(fp_line
			(start 0.12065 -0.3048)
			(end 0.67945 -0.3048)
			(stroke
				(width 0.1)
				(type default)
			)
			(layer "F.Fab")
		)
		(fp_line
			(start 0.12065 -0.2794)
			(end 0.12065 -0.3048)
			(stroke
				(width 0.1)
				(type default)
			)
			(layer "F.Fab")
		)
		(fp_line
			(start -0.12065 -0.2794)
			(end 0.12065 -0.2794)
			(stroke
				(width 0.1)
				(type default)
			)
			(layer "F.Fab")
		)
		(fp_line
			(start 0.120396 0.2794)
			(end -0.12065 0.2794)
			(stroke
				(width 0.1)
				(type default)
			)
			(layer "F.Fab")
		)
		(fp_line
			(start -0.12065 0.2794)
			(end -0.12065 0.3048)
			(stroke
				(width 0.1)
				(type default)
			)
			(layer "F.Fab")
		)
		(fp_line
			(start 0.67945 0.3048)
			(end 0.120396 0.3048)
			(stroke
				(width 0.1)
				(type default)
			)
			(layer "F.Fab")
		)
		(fp_line
			(start 0.120396 0.3048)
			(end 0.120396 0.2794)
			(stroke
				(width 0.1)
				(type default)
			)
			(layer "F.Fab")
		)
		(fp_line
			(start -0.12065 0.3048)
			(end -0.67945 0.3048)
			(stroke
				(width 0.1)
				(type default)
			)
			(layer "F.Fab")
		)
		(fp_line
			(start -0.67945 0.3048)
			(end -0.67945 -0.305054)
			(stroke
				(width 0.1)
				(type default)
			)
			(layer "F.Fab")
		)
		(pad "1" smd circle
			(at -0.40005 0 90)
			(size 0 0)
			(layers "F.Cu" "F.Mask" "F.Paste")
			(net "I3C3_SDA_R")
		)
		(pad "2" smd circle
			(at 0.40005 0 90)
			(size 0 0)
			(layers "F.Cu" "F.Mask" "F.Paste")
			(net "I3C3_SPD_SDA")
		)
	)
	(footprint ""
		(layer "F.Cu")
		(at 3.0734 -111.45266)
		(property "Reference" ""
			(at 0 0 0)
			(layer "F.SilkS")
			(hide yes)
			(effects
				(font
					(size 1.27 1.27)
				)
			)
		)
		(property "Value" ""
			(at 0 0 0)
			(layer "F.Fab")
			(effects
				(font
					(size 1.27 1.27)
				)
			)
		)
		(duplicate_pad_numbers_are_jumpers no)
		(pad "1" smd circle
			(at 0 0)
			(size 0.9906 0.9906)
			(layers "F.Cu" "F.Mask" "F.Paste")
			(net "Net_324")
		)
		(zone
			(layer "F.Cu")
			(hatch none 0.5)
			(connect_pads
				(clearance 0)
			)
			(min_thickness 0.25)
			(keepout
				(tracks not_allowed)
				(vias allowed)
				(pads allowed)
				(copperpour not_allowed)
				(footprints allowed)
			)
			(placement
				(enabled no)
				(sheetname "")
			)
			(fill
				(thermal_gap 0.5)
				(thermal_bridge_width 0.5)
				(island_removal_mode 0)
			)
			(polygon
				(pts
					(arc
						(start 4.699 -111.45266)
						(mid 1.4478 -111.45266)
						(end 4.699 -111.45266)
					)
				)
			)
		)
	)
)
